(kicad_pcb
	(version 20260206)
	(generator "pcbnew")
	(generator_version "10.0")
	(general
		(thickness 1.6)
		(legacy_teardrops no)
	)
	(paper "A4")
	(title_block
		(title "v1-chassis-manager — T6M_CM_d_v01_1031_1645.brd")
		(comment 1 "Open CloudServer (Microsoft) / footprints 1845-1854 of 2512")
	)
	(layers
		(0 "F.Cu" signal "TOP")
		(4 "In1.Cu" signal "GND1")
		(6 "In2.Cu" signal "IN1")
		(8 "In3.Cu" signal "VCC1")
		(10 "In4.Cu" signal "VCC2")
		(12 "In5.Cu" signal "GND2")
		(14 "In6.Cu" signal "IN2")
		(16 "In7.Cu" signal "IN3")
		(18 "In8.Cu" signal "GND3")
		(2 "B.Cu" signal "BOTTOM")
		(9 "F.Adhes" user "F.Adhesive")
		(11 "B.Adhes" user "B.Adhesive")
		(13 "F.Paste" user "Package Geometry/Pastemask Top")
		(15 "B.Paste" user "Package Geometry/Pastemask Bottom")
		(5 "F.SilkS" user "Ref Des/Silkscreen Top")
		(7 "B.SilkS" user "Ref Des/Silkscreen Bottom")
		(1 "F.Mask" user "Board Geometry/Soldermask Top")
		(3 "B.Mask" user "Board Geometry/Soldermask Bottom")
		(17 "Dwgs.User" user "User.Drawings")
		(19 "Cmts.User" user "User.Comments")
		(21 "Eco1.User" user "User.Eco1")
		(23 "Eco2.User" user "User.Eco2")
		(25 "Edge.Cuts" user "Board Geometry/Outline")
		(27 "Margin" user)
		(31 "F.CrtYd" user "Package Geometry/Place Bound Top")
		(29 "B.CrtYd" user "Package Geometry/Place Bound Bottom")
		(35 "F.Fab" user "Ref Des/Assembly Top")
		(33 "B.Fab" user "Ref Des/Assembly Bottom")
	)
	(footprint ""
		(layer "B.Cu")
		(at 110.44936 -181.649624 180)
		(property "Reference" "R717"
			(at 21.356828 -32.269176 0)
			(unlocked yes)
			(layer "B.SilkS")
			(effects
				(font
					(size 0.7874 0.5842)
					(thickness 0.1524)
				)
				(justify left mirror)
			)
		)
		(property "Value" ""
			(at 0 0 0)
			(layer "B.Fab")
			(effects
				(font
					(size 1.27 1.27)
				)
				(justify mirror)
			)
		)
		(duplicate_pad_numbers_are_jumpers no)
		(fp_line
			(start 0.7874 0.4064)
			(end 0.7874 -0.4064)
			(stroke
				(width 0.1524)
				(type default)
			)
			(layer "B.SilkS")
		)
		(fp_line
			(start 0.7874 -0.4064)
			(end -0.7874 -0.4064)
			(stroke
				(width 0.1524)
				(type default)
			)
			(layer "B.SilkS")
		)
		(fp_line
			(start -0.7874 0.4064)
			(end 0.7874 0.4064)
			(stroke
				(width 0.1524)
				(type default)
			)
			(layer "B.SilkS")
		)
		(fp_line
			(start -0.7874 -0.4064)
			(end -0.7874 0.4064)
			(stroke
				(width 0.1524)
				(type default)
			)
			(layer "B.SilkS")
		)
		(fp_poly
			(pts
				(xy 0.508 0.2794) (xy 0.508 0.2286) (xy 0.635 0.2286) (xy 0.635 -0.254) (xy 0.5334 -0.254) (xy 0.5334 -0.2794)
				(xy -0.5334 -0.2794) (xy -0.5334 -0.254) (xy -0.635 -0.254) (xy -0.635 0.254) (xy -0.5334 0.254)
				(xy -0.5334 0.2794)
			)
			(stroke
				(width 0)
				(type default)
			)
			(fill no)
			(layer "B.CrtYd")
		)
		(pad "1" smd rect
			(at -0.40005 0)
			(size 0.4572 0.508)
			(layers "B.Cu" "B.Mask" "B.Paste")
			(net "T6_NODE4_EN")
		)
		(pad "2" smd rect
			(at 0.40005 0)
			(size 0.4572 0.508)
			(layers "B.Cu" "B.Mask" "B.Paste")
			(net "P5V_NODE1")
		)
	)
	(footprint ""
		(layer "B.Cu")
		(at 156.828998 -149.76983)
		(property "Reference" "C442"
			(at 1.026414 3.42265 0)
			(unlocked yes)
			(layer "B.SilkS")
			(effects
				(font
					(size 0.7874 0.5842)
					(thickness 0.1524)
				)
				(justify left mirror)
			)
		)
		(property "Value" ""
			(at 0 0 0)
			(layer "B.Fab")
			(effects
				(font
					(size 1.27 1.27)
				)
				(justify mirror)
			)
		)
		(duplicate_pad_numbers_are_jumpers no)
		(fp_line
			(start -0.7874 -0.4064)
			(end -0.7874 0.4064)
			(stroke
				(width 0.1524)
				(type default)
			)
			(layer "B.SilkS")
		)
		(fp_line
			(start -0.7874 0.4064)
			(end 0.7874 0.4064)
			(stroke
				(width 0.1524)
				(type default)
			)
			(layer "B.SilkS")
		)
		(fp_line
			(start 0 0.381)
			(end 0 -0.381)
			(stroke
				(width 0.1524)
				(type default)
			)
			(layer "B.SilkS")
		)
		(fp_line
			(start 0.7874 -0.4064)
			(end -0.7874 -0.4064)
			(stroke
				(width 0.1524)
				(type default)
			)
			(layer "B.SilkS")
		)
		(fp_line
			(start 0.7874 0.4064)
			(end 0.7874 -0.4064)
			(stroke
				(width 0.1524)
				(type default)
			)
			(layer "B.SilkS")
		)
		(fp_poly
			(pts
				(xy 0.5334 0.254) (xy 0.635 0.254) (xy 0.635 0.2286) (xy 0.635 -0.254) (xy 0.5334 -0.254) (xy 0.5334 -0.2794)
				(xy -0.5334 -0.2794) (xy -0.5334 -0.254) (xy -0.635 -0.254) (xy -0.635 0.254) (xy -0.5334 0.254)
				(xy -0.5334 0.2794) (xy 0.508 0.2794) (xy 0.5334 0.2794)
			)
			(stroke
				(width 0)
				(type default)
			)
			(fill no)
			(layer "B.CrtYd")
		)
		(pad "1" smd rect
			(at -0.40005 0 180)
			(size 0.4572 0.508)
			(layers "B.Cu" "B.Mask" "B.Paste")
			(net "P3V3_NODE1")
		)
		(pad "2" smd rect
			(at 0.40005 0 180)
			(size 0.4572 0.508)
			(layers "B.Cu" "B.Mask" "B.Paste")
			(net "GND")
		)
	)
	(footprint ""
		(layer "B.Cu")
		(at 55.81015 -74.444352 180)
		(property "Reference" "C121"
			(at 13.409168 -31.563056 0)
			(unlocked yes)
			(layer "B.SilkS")
			(effects
				(font
					(size 0.7874 0.5842)
					(thickness 0.1524)
				)
				(justify left mirror)
			)
		)
		(property "Value" ""
			(at 0 0 0)
			(layer "B.Fab")
			(effects
				(font
					(size 1.27 1.27)
				)
				(justify mirror)
			)
		)
		(duplicate_pad_numbers_are_jumpers no)
		(fp_line
			(start 0.7874 0.4064)
			(end 0.7874 -0.4064)
			(stroke
				(width 0.1524)
				(type default)
			)
			(layer "B.SilkS")
		)
		(fp_line
			(start 0.7874 -0.4064)
			(end -0.7874 -0.4064)
			(stroke
				(width 0.1524)
				(type default)
			)
			(layer "B.SilkS")
		)
		(fp_line
			(start 0 0.381)
			(end 0 -0.381)
			(stroke
				(width 0.1524)
				(type default)
			)
			(layer "B.SilkS")
		)
		(fp_line
			(start -0.7874 0.4064)
			(end 0.7874 0.4064)
			(stroke
				(width 0.1524)
				(type default)
			)
			(layer "B.SilkS")
		)
		(fp_line
			(start -0.7874 -0.4064)
			(end -0.7874 0.4064)
			(stroke
				(width 0.1524)
				(type default)
			)
			(layer "B.SilkS")
		)
		(fp_poly
			(pts
				(xy 0.5334 0.254) (xy 0.635 0.254) (xy 0.635 0.2286) (xy 0.635 -0.254) (xy 0.5334 -0.254) (xy 0.5334 -0.2794)
				(xy -0.5334 -0.2794) (xy -0.5334 -0.254) (xy -0.635 -0.254) (xy -0.635 0.254) (xy -0.5334 0.254)
				(xy -0.5334 0.2794) (xy 0.508 0.2794) (xy 0.5334 0.2794)
			)
			(stroke
				(width 0)
				(type default)
			)
			(fill no)
			(layer "B.CrtYd")
		)
		(pad "1" smd rect
			(at -0.40005 0)
			(size 0.4572 0.508)
			(layers "B.Cu" "B.Mask" "B.Paste")
			(net "P1V05_NODE1")
		)
		(pad "2" smd rect
			(at 0.40005 0)
			(size 0.4572 0.508)
			(layers "B.Cu" "B.Mask" "B.Paste")
			(net "GND")
		)
	)
	(footprint ""
		(layer "B.Cu")
		(at 66.194686 -121.044462 90)
		(property "Reference" "R325"
			(at -7.37235 9.910826 270)
			(unlocked yes)
			(layer "B.SilkS")
			(effects
				(font
					(size 0.7874 0.5842)
					(thickness 0.1524)
				)
				(justify left mirror)
			)
		)
		(property "Value" ""
			(at 0 0 90)
			(layer "B.Fab")
			(effects
				(font
					(size 1.27 1.27)
				)
				(justify mirror)
			)
		)
		(duplicate_pad_numbers_are_jumpers no)
		(fp_line
			(start 0.7874 -0.4064)
			(end -0.7874 -0.4064)
			(stroke
				(width 0.1524)
				(type default)
			)
			(layer "B.SilkS")
		)
		(fp_line
			(start -0.7874 -0.4064)
			(end -0.7874 0.4064)
			(stroke
				(width 0.1524)
				(type default)
			)
			(layer "B.SilkS")
		)
		(fp_line
			(start 0.7874 0.4064)
			(end 0.7874 -0.4064)
			(stroke
				(width 0.1524)
				(type default)
			)
			(layer "B.SilkS")
		)
		(fp_line
			(start -0.7874 0.4064)
			(end 0.7874 0.4064)
			(stroke
				(width 0.1524)
				(type default)
			)
			(layer "B.SilkS")
		)
		(fp_poly
			(pts
				(xy 0.508 0.2794) (xy 0.508 0.2286) (xy 0.635 0.2286) (xy 0.635 -0.254) (xy 0.5334 -0.254) (xy 0.5334 -0.2794)
				(xy -0.5334 -0.2794) (xy -0.5334 -0.254) (xy -0.635 -0.254) (xy -0.635 0.254) (xy -0.5334 0.254)
				(xy -0.5334 0.2794)
			)
			(stroke
				(width 0)
				(type default)
			)
			(fill no)
			(layer "B.CrtYd")
		)
		(pad "1" smd rect
			(at -0.40005 0 270)
			(size 0.4572 0.508)
			(layers "B.Cu" "B.Mask" "B.Paste")
			(net "P3V3_NODE1")
		)
		(pad "2" smd rect
			(at 0.40005 0 270)
			(size 0.4572 0.508)
			(layers "B.Cu" "B.Mask" "B.Paste")
			(net "BMC_ROMA9")
		)
	)
	(footprint ""
		(layer "B.Cu")
		(at 46.281086 -132.093462 180)
		(property "Reference" "C223"
			(at -4.582414 -0.37211 0)
			(unlocked yes)
			(layer "B.SilkS")
			(effects
				(font
					(size 0.7874 0.5842)
					(thickness 0.1524)
				)
				(justify left mirror)
			)
		)
		(property "Value" ""
			(at 0 0 0)
			(layer "B.Fab")
			(effects
				(font
					(size 1.27 1.27)
				)
				(justify mirror)
			)
		)
		(duplicate_pad_numbers_are_jumpers no)
		(fp_line
			(start 0.7874 0.4064)
			(end 0.7874 -0.4064)
			(stroke
				(width 0.1524)
				(type default)
			)
			(layer "B.SilkS")
		)
		(fp_line
			(start 0.7874 -0.4064)
			(end -0.7874 -0.4064)
			(stroke
				(width 0.1524)
				(type default)
			)
			(layer "B.SilkS")
		)
		(fp_line
			(start 0 0.381)
			(end 0 -0.381)
			(stroke
				(width 0.1524)
				(type default)
			)
			(layer "B.SilkS")
		)
		(fp_line
			(start -0.7874 0.4064)
			(end 0.7874 0.4064)
			(stroke
				(width 0.1524)
				(type default)
			)
			(layer "B.SilkS")
		)
		(fp_line
			(start -0.7874 -0.4064)
			(end -0.7874 0.4064)
			(stroke
				(width 0.1524)
				(type default)
			)
			(layer "B.SilkS")
		)
		(fp_poly
			(pts
				(xy 0.5334 0.254) (xy 0.635 0.254) (xy 0.635 0.2286) (xy 0.635 -0.254) (xy 0.5334 -0.254) (xy 0.5334 -0.2794)
				(xy -0.5334 -0.2794) (xy -0.5334 -0.254) (xy -0.635 -0.254) (xy -0.635 0.254) (xy -0.5334 0.254)
				(xy -0.5334 0.2794) (xy 0.508 0.2794) (xy 0.5334 0.2794)
			)
			(stroke
				(width 0)
				(type default)
			)
			(fill no)
			(layer "B.CrtYd")
		)
		(pad "1" smd rect
			(at -0.40005 0)
			(size 0.4572 0.508)
			(layers "B.Cu" "B.Mask" "B.Paste")
			(net "GND")
		)
		(pad "2" smd rect
			(at 0.40005 0)
			(size 0.4572 0.508)
			(layers "B.Cu" "B.Mask" "B.Paste")
			(net "P0V75_BMC_VTTREF_NODE1")
		)
	)
	(footprint ""
		(layer "B.Cu")
		(at 58.879486 -146.419062 90)
		(property "Reference" "R290"
			(at 1.521206 -1.398778 270)
			(unlocked yes)
			(layer "B.SilkS")
			(effects
				(font
					(size 0.7874 0.5842)
					(thickness 0.1524)
				)
				(justify left mirror)
			)
		)
		(property "Value" ""
			(at 0 0 90)
			(layer "B.Fab")
			(effects
				(font
					(size 1.27 1.27)
				)
				(justify mirror)
			)
		)
		(duplicate_pad_numbers_are_jumpers no)
		(fp_line
			(start 0.7874 -0.4064)
			(end -0.7874 -0.4064)
			(stroke
				(width 0.1524)
				(type default)
			)
			(layer "B.SilkS")
		)
		(fp_line
			(start -0.7874 -0.4064)
			(end -0.7874 0.4064)
			(stroke
				(width 0.1524)
				(type default)
			)
			(layer "B.SilkS")
		)
		(fp_line
			(start 0.7874 0.4064)
			(end 0.7874 -0.4064)
			(stroke
				(width 0.1524)
				(type default)
			)
			(layer "B.SilkS")
		)
		(fp_line
			(start -0.7874 0.4064)
			(end 0.7874 0.4064)
			(stroke
				(width 0.1524)
				(type default)
			)
			(layer "B.SilkS")
		)
		(fp_poly
			(pts
				(xy 0.508 0.2794) (xy 0.508 0.2286) (xy 0.635 0.2286) (xy 0.635 -0.254) (xy 0.5334 -0.254) (xy 0.5334 -0.2794)
				(xy -0.5334 -0.2794) (xy -0.5334 -0.254) (xy -0.635 -0.254) (xy -0.635 0.254) (xy -0.5334 0.254)
				(xy -0.5334 0.2794)
			)
			(stroke
				(width 0)
				(type default)
			)
			(fill no)
			(layer "B.CrtYd")
		)
		(pad "1" smd rect
			(at -0.40005 0 270)
			(size 0.4572 0.508)
			(layers "B.Cu" "B.Mask" "B.Paste")
			(net "BMC_NODE1_GFX_BLUE")
		)
		(pad "2" smd rect
			(at 0.40005 0 270)
			(size 0.4572 0.508)
			(layers "B.Cu" "B.Mask" "B.Paste")
			(net "GND")
		)
	)
	(footprint ""
		(layer "B.Cu")
		(at 56.171338 -81.182718 180)
		(property "Reference" "C57"
			(at 13.617956 -30.014672 0)
			(unlocked yes)
			(layer "B.SilkS")
			(effects
				(font
					(size 0.7874 0.5842)
					(thickness 0.1524)
				)
				(justify left mirror)
			)
		)
		(property "Value" ""
			(at 0 0 0)
			(layer "B.Fab")
			(effects
				(font
					(size 1.27 1.27)
				)
				(justify mirror)
			)
		)
		(duplicate_pad_numbers_are_jumpers no)
		(fp_line
			(start 0.7874 0.4064)
			(end 0.7874 -0.4064)
			(stroke
				(width 0.1524)
				(type default)
			)
			(layer "B.SilkS")
		)
		(fp_line
			(start 0.7874 -0.4064)
			(end -0.7874 -0.4064)
			(stroke
				(width 0.1524)
				(type default)
			)
			(layer "B.SilkS")
		)
		(fp_line
			(start 0 0.381)
			(end 0 -0.381)
			(stroke
				(width 0.1524)
				(type default)
			)
			(layer "B.SilkS")
		)
		(fp_line
			(start -0.7874 0.4064)
			(end 0.7874 0.4064)
			(stroke
				(width 0.1524)
				(type default)
			)
			(layer "B.SilkS")
		)
		(fp_line
			(start -0.7874 -0.4064)
			(end -0.7874 0.4064)
			(stroke
				(width 0.1524)
				(type default)
			)
			(layer "B.SilkS")
		)
		(fp_poly
			(pts
				(xy 0.5334 0.254) (xy 0.635 0.254) (xy 0.635 0.2286) (xy 0.635 -0.254) (xy 0.5334 -0.254) (xy 0.5334 -0.2794)
				(xy -0.5334 -0.2794) (xy -0.5334 -0.254) (xy -0.635 -0.254) (xy -0.635 0.254) (xy -0.5334 0.254)
				(xy -0.5334 0.2794) (xy 0.508 0.2794) (xy 0.5334 0.2794)
			)
			(stroke
				(width 0)
				(type default)
			)
			(fill no)
			(layer "B.CrtYd")
		)
		(pad "1" smd rect
			(at -0.40005 0)
			(size 0.4572 0.508)
			(layers "B.Cu" "B.Mask" "B.Paste")
			(net "P1V05_NODE1")
		)
		(pad "2" smd rect
			(at 0.40005 0)
			(size 0.4572 0.508)
			(layers "B.Cu" "B.Mask" "B.Paste")
			(net "GND")
		)
	)
	(footprint ""
		(layer "B.Cu")
		(at 88.43518 -84.118704)
		(property "Reference" "C34"
			(at 0.271272 -1.659382 0)
			(unlocked yes)
			(layer "B.SilkS")
			(effects
				(font
					(size 0.7874 0.5842)
					(thickness 0.1524)
				)
				(justify left mirror)
			)
		)
		(property "Value" ""
			(at 0 0 0)
			(layer "B.Fab")
			(effects
				(font
					(size 1.27 1.27)
				)
				(justify mirror)
			)
		)
		(duplicate_pad_numbers_are_jumpers no)
		(fp_line
			(start -1.905 -0.8636)
			(end -1.905 0.8636)
			(stroke
				(width 0.1524)
				(type default)
			)
			(layer "B.SilkS")
		)
		(fp_line
			(start -1.905 0.8636)
			(end 1.905 0.8636)
			(stroke
				(width 0.1524)
				(type default)
			)
			(layer "B.SilkS")
		)
		(fp_line
			(start 0 0.8382)
			(end 0 -0.8382)
			(stroke
				(width 0.1524)
				(type default)
			)
			(layer "B.SilkS")
		)
		(fp_line
			(start 1.905 -0.8636)
			(end -1.905 -0.8636)
			(stroke
				(width 0.1524)
				(type default)
			)
			(layer "B.SilkS")
		)
		(fp_line
			(start 1.905 0.8636)
			(end 1.905 -0.8636)
			(stroke
				(width 0.1524)
				(type default)
			)
			(layer "B.SilkS")
		)
		(fp_rect
			(start 1.524 0.7366)
			(end -1.524 -0.7366)
			(stroke
				(width 0)
				(type default)
			)
			(fill no)
			(layer "B.CrtYd")
		)
		(pad "1" smd rect
			(at -0.94996 0 180)
			(size 1.1176 1.3716)
			(layers "B.Cu" "B.Mask" "B.Paste")
			(net "P3V3_RTC_NODE1")
		)
		(pad "2" smd rect
			(at 0.94996 0 180)
			(size 1.1176 1.3716)
			(layers "B.Cu" "B.Mask" "B.Paste")
			(net "GND")
		)
	)
	(footprint ""
		(layer "B.Cu")
		(at 141.099032 -163.498022 90)
		(property "Reference" "R995"
			(at -4.650486 -0.070866 270)
			(unlocked yes)
			(layer "B.SilkS")
			(effects
				(font
					(size 0.7874 0.5842)
					(thickness 0.1524)
				)
				(justify left mirror)
			)
		)
		(property "Value" ""
			(at 0 0 90)
			(layer "B.Fab")
			(effects
				(font
					(size 1.27 1.27)
				)
				(justify mirror)
			)
		)
		(duplicate_pad_numbers_are_jumpers no)
		(fp_line
			(start 0.7874 -0.4064)
			(end -0.7874 -0.4064)
			(stroke
				(width 0.1524)
				(type default)
			)
			(layer "B.SilkS")
		)
		(fp_line
			(start -0.7874 -0.4064)
			(end -0.7874 0.4064)
			(stroke
				(width 0.1524)
				(type default)
			)
			(layer "B.SilkS")
		)
		(fp_line
			(start 0.7874 0.4064)
			(end 0.7874 -0.4064)
			(stroke
				(width 0.1524)
				(type default)
			)
			(layer "B.SilkS")
		)
		(fp_line
			(start -0.7874 0.4064)
			(end 0.7874 0.4064)
			(stroke
				(width 0.1524)
				(type default)
			)
			(layer "B.SilkS")
		)
		(fp_poly
			(pts
				(xy 0.508 0.2794) (xy 0.508 0.2286) (xy 0.635 0.2286) (xy 0.635 -0.254) (xy 0.5334 -0.254) (xy 0.5334 -0.2794)
				(xy -0.5334 -0.2794) (xy -0.5334 -0.254) (xy -0.635 -0.254) (xy -0.635 0.254) (xy -0.5334 0.254)
				(xy -0.5334 0.2794)
			)
			(stroke
				(width 0)
				(type default)
			)
			(fill no)
			(layer "B.CrtYd")
		)
		(pad "1" smd rect
			(at -0.40005 0 270)
			(size 0.4572 0.508)
			(layers "B.Cu" "B.Mask" "B.Paste")
			(net "UART_T10_NODE3_TXD")
		)
		(pad "2" smd rect
			(at 0.40005 0 270)
			(size 0.4572 0.508)
			(layers "B.Cu" "B.Mask" "B.Paste")
			(net "UART_T10_NODE3_TXD_R")
		)
	)
	(footprint ""
		(layer "B.Cu")
		(at 70.97776 -188.126624 90)
		(property "Reference" "R920"
			(at 4.318254 -0.346202 270)
			(unlocked yes)
			(layer "B.SilkS")
			(effects
				(font
					(size 0.7874 0.5842)
					(thickness 0.1524)
				)
				(justify left mirror)
			)
		)
		(property "Value" ""
			(at 0 0 90)
			(layer "B.Fab")
			(effects
				(font
					(size 1.27 1.27)
				)
				(justify mirror)
			)
		)
		(duplicate_pad_numbers_are_jumpers no)
		(fp_line
			(start 0.7874 -0.4064)
			(end -0.7874 -0.4064)
			(stroke
				(width 0.1524)
				(type default)
			)
			(layer "B.SilkS")
		)
		(fp_line
			(start -0.7874 -0.4064)
			(end -0.7874 0.4064)
			(stroke
				(width 0.1524)
				(type default)
			)
			(layer "B.SilkS")
		)
		(fp_line
			(start 0.7874 0.4064)
			(end 0.7874 -0.4064)
			(stroke
				(width 0.1524)
				(type default)
			)
			(layer "B.SilkS")
		)
		(fp_line
			(start -0.7874 0.4064)
			(end 0.7874 0.4064)
			(stroke
				(width 0.1524)
				(type default)
			)
			(layer "B.SilkS")
		)
		(fp_poly
			(pts
				(xy 0.508 0.2794) (xy 0.508 0.2286) (xy 0.635 0.2286) (xy 0.635 -0.254) (xy 0.5334 -0.254) (xy 0.5334 -0.2794)
				(xy -0.5334 -0.2794) (xy -0.5334 -0.254) (xy -0.635 -0.254) (xy -0.635 0.254) (xy -0.5334 0.254)
				(xy -0.5334 0.2794)
			)
			(stroke
				(width 0)
				(type default)
			)
			(fill no)
			(layer "B.CrtYd")
		)
		(pad "1" smd rect
			(at -0.40005 0 270)
			(size 0.4572 0.508)
			(layers "B.Cu" "B.Mask" "B.Paste")
			(net "UART_T3_NODE3_RXD")
		)
		(pad "2" smd rect
			(at 0.40005 0 270)
			(size 0.4572 0.508)
			(layers "B.Cu" "B.Mask" "B.Paste")
			(net "UART_T3_NODE3_RXD_R")
		)
	)
)
